# T6G (Grand Teton) — schematic netlist excerpt (pin names and nets, part order shuffled) for the footprints in the layout excerpt that follows; sources: Cadence DE-HDL packaged netlist, KiCad conversion of 04192023_DAF0TMB3IC0_F0TG_MB_C_brd_V02_OCP.brd

R6325  Q_RES  10K 1% CHIP  pkg 0402LF  page 178 : A = USB_HUB2_TI_TEST ; B = GND
R816  Q_RES  10K 5% CHIP  pkg 0402LF  page 164 : A = PVDD18_S5_P0 ; B = UART_CPU0_SCM_UART1_RX

(kicad_pcb
	(version 20260206)
	(generator "pcbnew")
	(generator_version "10.0")
	(general
		(thickness 1.6)
		(legacy_teardrops no)
	)
	(paper "A4")
	(title_block
		(title "04192023_DAF0TMB3IC0_F0TG_MB_C_brd_V02_OCP.brd")
		(comment 1 "Grand Teton / footprints 2385-2386 of 8354")
	)
	(layers
		(0 "F.Cu" signal "TOP")
		(4 "In1.Cu" signal "GND")
		(6 "In2.Cu" signal "IN1")
		(8 "In3.Cu" signal "GND1")
		(10 "In4.Cu" signal "IN2")
		(12 "In5.Cu" signal "GND2")
		(14 "In6.Cu" signal "IN3")
		(16 "In7.Cu" signal "GND3")
		(18 "In8.Cu" signal "VCC")
		(20 "In9.Cu" signal "VCC1")
		(22 "In10.Cu" signal "GND4")
		(24 "In11.Cu" signal "IN4")
		(26 "In12.Cu" signal "GND5")
		(28 "In13.Cu" signal "IN5")
		(30 "In14.Cu" signal "GND6")
		(32 "In15.Cu" signal "IN6")
		(34 "In16.Cu" signal "GND7")
		(2 "B.Cu" signal "BOTTOM")
		(9 "F.Adhes" user "F.Adhesive")
		(11 "B.Adhes" user "B.Adhesive")
		(13 "F.Paste" user "Package Geometry/Pastemask Top")
		(15 "B.Paste" user "Package Geometry/Pastemask Bottom")
		(5 "F.SilkS" user "Ref Des/Silkscreen Top")
		(7 "B.SilkS" user "Ref Des/Silkscreen Bottom")
		(1 "F.Mask" user "Board Geometry/Soldermask Top")
		(3 "B.Mask" user "Board Geometry/Soldermask Bottom")
		(17 "Dwgs.User" user "User.Drawings")
		(19 "Cmts.User" user "User.Comments")
		(21 "Eco1.User" user "User.Eco1")
		(23 "Eco2.User" user "User.Eco2")
		(25 "Edge.Cuts" user "Board Geometry/Outline")
		(27 "Margin" user)
		(31 "F.CrtYd" user "Package Geometry/Place Bound Top")
		(29 "B.CrtYd" user "Package Geometry/Place Bound Bottom")
		(35 "F.Fab" user "Ref Des/Assembly Top")
		(33 "B.Fab" user "Ref Des/Assembly Bottom")
	)
	(footprint ""
		(layer "F.Cu")
		(at 101.760528 -36.25215 90)
		(property "Reference" "R6325"
			(at 0 0 90)
			(layer "F.SilkS")
			(hide yes)
			(effects
				(font
					(size 1.27 1.27)
				)
			)
		)
		(property "Value" ""
			(at 0 0 90)
			(layer "F.Fab")
			(effects
				(font
					(size 1.27 1.27)
				)
			)
		)
		(duplicate_pad_numbers_are_jumpers no)
		(fp_line
			(start 0.7874 -0.4064)
			(end 0.7874 0.4064)
			(stroke
				(width 0.1524)
				(type default)
			)
			(layer "F.SilkS")
		)
		(fp_line
			(start -0.7874 -0.4064)
			(end 0.7874 -0.4064)
			(stroke
				(width 0.1524)
				(type default)
			)
			(layer "F.SilkS")
		)
		(fp_line
			(start 0.7874 0.4064)
			(end -0.7874 0.4064)
			(stroke
				(width 0.1524)
				(type default)
			)
			(layer "F.SilkS")
		)
		(fp_line
			(start -0.7874 0.4064)
			(end -0.7874 -0.4064)
			(stroke
				(width 0.1524)
				(type default)
			)
			(layer "F.SilkS")
		)
		(fp_line
			(start -0.12065 -0.305054)
			(end -0.12065 -0.2794)
			(stroke
				(width 0.1)
				(type default)
			)
			(layer "F.Fab")
		)
		(fp_line
			(start -0.67945 -0.305054)
			(end -0.12065 -0.305054)
			(stroke
				(width 0.1)
				(type default)
			)
			(layer "F.Fab")
		)
		(fp_line
			(start 0.67945 -0.3048)
			(end 0.67945 0.3048)
			(stroke
				(width 0.1)
				(type default)
			)
			(layer "F.Fab")
		)
		(fp_line
			(start 0.12065 -0.3048)
			(end 0.67945 -0.3048)
			(stroke
				(width 0.1)
				(type default)
			)
			(layer "F.Fab")
		)
		(fp_line
			(start 0.12065 -0.2794)
			(end 0.12065 -0.3048)
			(stroke
				(width 0.1)
				(type default)
			)
			(layer "F.Fab")
		)
		(fp_line
			(start -0.12065 -0.2794)
			(end 0.12065 -0.2794)
			(stroke
				(width 0.1)
				(type default)
			)
			(layer "F.Fab")
		)
		(fp_line
			(start 0.120396 0.2794)
			(end -0.12065 0.2794)
			(stroke
				(width 0.1)
				(type default)
			)
			(layer "F.Fab")
		)
		(fp_line
			(start -0.12065 0.2794)
			(end -0.12065 0.3048)
			(stroke
				(width 0.1)
				(type default)
			)
			(layer "F.Fab")
		)
		(fp_line
			(start 0.67945 0.3048)
			(end 0.120396 0.3048)
			(stroke
				(width 0.1)
				(type default)
			)
			(layer "F.Fab")
		)
		(fp_line
			(start 0.120396 0.3048)
			(end 0.120396 0.2794)
			(stroke
				(width 0.1)
				(type default)
			)
			(layer "F.Fab")
		)
		(fp_line
			(start -0.12065 0.3048)
			(end -0.67945 0.3048)
			(stroke
				(width 0.1)
				(type default)
			)
			(layer "F.Fab")
		)
		(fp_line
			(start -0.67945 0.3048)
			(end -0.67945 -0.305054)
			(stroke
				(width 0.1)
				(type default)
			)
			(layer "F.Fab")
		)
		(pad "1" smd circle
			(at -0.40005 0 90)
			(size 0 0)
			(layers "F.Cu" "F.Mask" "F.Paste")
			(net "USB_HUB2_TI_TEST")
		)
		(pad "2" smd circle
			(at 0.40005 0 90)
			(size 0 0)
			(layers "F.Cu" "F.Mask" "F.Paste")
			(net "GND")
		)
	)
	(footprint ""
		(layer "F.Cu")
		(at 368.241326 -45.267118 -90)
		(property "Reference" "R816"
			(at 0 0 270)
			(layer "F.SilkS")
			(hide yes)
			(effects
				(font
					(size 1.27 1.27)
				)
			)
		)
		(property "Value" ""
			(at 0 0 270)
			(layer "F.Fab")
			(effects
				(font
					(size 1.27 1.27)
				)
			)
		)
		(duplicate_pad_numbers_are_jumpers no)
		(fp_line
			(start -0.7874 0.4064)
			(end -0.7874 -0.4064)
			(stroke
				(width 0.1524)
				(type default)
			)
			(layer "F.SilkS")
		)
		(fp_line
			(start 0.7874 0.4064)
			(end -0.7874 0.4064)
			(stroke
				(width 0.1524)
				(type default)
			)
			(layer "F.SilkS")
		)
		(fp_line
			(start -0.7874 -0.4064)
			(end 0.7874 -0.4064)
			(stroke
				(width 0.1524)
				(type default)
			)
			(layer "F.SilkS")
		)
		(fp_line
			(start 0.7874 -0.4064)
			(end 0.7874 0.4064)
			(stroke
				(width 0.1524)
				(type default)
			)
			(layer "F.SilkS")
		)
		(fp_line
			(start -0.67945 0.3048)
			(end -0.67945 -0.305054)
			(stroke
				(width 0.1)
				(type default)
			)
			(layer "F.Fab")
		)
		(fp_line
			(start -0.12065 0.3048)
			(end -0.67945 0.3048)
			(stroke
				(width 0.1)
				(type default)
			)
			(layer "F.Fab")
		)
		(fp_line
			(start 0.120396 0.3048)
			(end 0.120396 0.2794)
			(stroke
				(width 0.1)
				(type default)
			)
			(layer "F.Fab")
		)
		(fp_line
			(start 0.67945 0.3048)
			(end 0.120396 0.3048)
			(stroke
				(width 0.1)
				(type default)
			)
			(layer "F.Fab")
		)
		(fp_line
			(start -0.12065 0.2794)
			(end -0.12065 0.3048)
			(stroke
				(width 0.1)
				(type default)
			)
			(layer "F.Fab")
		)
		(fp_line
			(start 0.120396 0.2794)
			(end -0.12065 0.2794)
			(stroke
				(width 0.1)
				(type default)
			)
			(layer "F.Fab")
		)
		(fp_line
			(start -0.12065 -0.2794)
			(end 0.12065 -0.2794)
			(stroke
				(width 0.1)
				(type default)
			)
			(layer "F.Fab")
		)
		(fp_line
			(start 0.12065 -0.2794)
			(end 0.12065 -0.3048)
			(stroke
				(width 0.1)
				(type default)
			)
			(layer "F.Fab")
		)
		(fp_line
			(start 0.12065 -0.3048)
			(end 0.67945 -0.3048)
			(stroke
				(width 0.1)
				(type default)
			)
			(layer "F.Fab")
		)
		(fp_line
			(start 0.67945 -0.3048)
			(end 0.67945 0.3048)
			(stroke
				(width 0.1)
				(type default)
			)
			(layer "F.Fab")
		)
		(fp_line
			(start -0.67945 -0.305054)
			(end -0.12065 -0.305054)
			(stroke
				(width 0.1)
				(type default)
			)
			(layer "F.Fab")
		)
		(fp_line
			(start -0.12065 -0.305054)
			(end -0.12065 -0.2794)
			(stroke
				(width 0.1)
				(type default)
			)
			(layer "F.Fab")
		)
		(pad "1" smd circle
			(at -0.40005 0 270)
			(size 0 0)
			(layers "F.Cu" "F.Mask" "F.Paste")
			(net "PVDD18_S5_P0")
		)
		(pad "2" smd circle
			(at 0.40005 0 270)
			(size 0 0)
			(layers "F.Cu" "F.Mask" "F.Paste")
			(net "UART_CPU0_SCM_UART1_RX")
		)
	)
)
